# T6G (Grand Teton) — schematic netlist excerpt (pin names and nets, part order shuffled) for the footprints in the layout excerpt that follows; sources: Cadence DE-HDL packaged netlist, KiCad conversion of 04192023_DAF0TMB3IC0_F0TG_MB_C_brd_V02_OCP.brd

R3617  Q_RES  4.7K 1% EMPTY  pkg 0402LF  page 236 : A = GND ; B = INA230_1_A0
PR3970  Q_RES  2.67K 1% CHIP  pkg 0402LF  page 146 : A = P12V_E1S_SENSE_0 ; B = GND
C713  Q_CAP_DIFFBUS  DIFF BUS_0.22UF 6.3V 20% X6S  pkg C0201  page 66 : \1\ = P5E_CPU1_P1_TX_C_DP<14> ; \2\ = P5E_CPU1_P1_TX_DP<14>

(kicad_pcb
	(version 20260206)
	(generator "pcbnew")
	(generator_version "10.0")
	(general
		(thickness 1.6)
		(legacy_teardrops no)
	)
	(paper "A4")
	(title_block
		(title "04192023_DAF0TMB3IC0_F0TG_MB_C_brd_V02_OCP.brd")
		(comment 1 "Grand Teton / footprints 132-134 of 8354")
	)
	(layers
		(0 "F.Cu" signal "TOP")
		(4 "In1.Cu" signal "GND")
		(6 "In2.Cu" signal "IN1")
		(8 "In3.Cu" signal "GND1")
		(10 "In4.Cu" signal "IN2")
		(12 "In5.Cu" signal "GND2")
		(14 "In6.Cu" signal "IN3")
		(16 "In7.Cu" signal "GND3")
		(18 "In8.Cu" signal "VCC")
		(20 "In9.Cu" signal "VCC1")
		(22 "In10.Cu" signal "GND4")
		(24 "In11.Cu" signal "IN4")
		(26 "In12.Cu" signal "GND5")
		(28 "In13.Cu" signal "IN5")
		(30 "In14.Cu" signal "GND6")
		(32 "In15.Cu" signal "IN6")
		(34 "In16.Cu" signal "GND7")
		(2 "B.Cu" signal "BOTTOM")
		(9 "F.Adhes" user "F.Adhesive")
		(11 "B.Adhes" user "B.Adhesive")
		(13 "F.Paste" user "Package Geometry/Pastemask Top")
		(15 "B.Paste" user "Package Geometry/Pastemask Bottom")
		(5 "F.SilkS" user "Ref Des/Silkscreen Top")
		(7 "B.SilkS" user "Ref Des/Silkscreen Bottom")
		(1 "F.Mask" user "Board Geometry/Soldermask Top")
		(3 "B.Mask" user "Board Geometry/Soldermask Bottom")
		(17 "Dwgs.User" user "User.Drawings")
		(19 "Cmts.User" user "User.Comments")
		(21 "Eco1.User" user "User.Eco1")
		(23 "Eco2.User" user "User.Eco2")
		(25 "Edge.Cuts" user "Board Geometry/Outline")
		(27 "Margin" user)
		(31 "F.CrtYd" user "Package Geometry/Place Bound Top")
		(29 "B.CrtYd" user "Package Geometry/Place Bound Bottom")
		(35 "F.Fab" user "Ref Des/Assembly Top")
		(33 "B.Fab" user "Ref Des/Assembly Bottom")
	)
	(footprint ""
		(layer "F.Cu")
		(at 253.97841 -45.865542 90)
		(property "Reference" "PR3970"
			(at 0 0 90)
			(layer "F.SilkS")
			(hide yes)
			(effects
				(font
					(size 1.27 1.27)
				)
			)
		)
		(property "Value" ""
			(at 0 0 90)
			(layer "F.Fab")
			(effects
				(font
					(size 1.27 1.27)
				)
			)
		)
		(duplicate_pad_numbers_are_jumpers no)
		(fp_line
			(start 0.7874 -0.4064)
			(end 0.7874 0.4064)
			(stroke
				(width 0.1524)
				(type default)
			)
			(layer "F.SilkS")
		)
		(fp_line
			(start -0.7874 -0.4064)
			(end 0.7874 -0.4064)
			(stroke
				(width 0.1524)
				(type default)
			)
			(layer "F.SilkS")
		)
		(fp_line
			(start 0.7874 0.4064)
			(end -0.7874 0.4064)
			(stroke
				(width 0.1524)
				(type default)
			)
			(layer "F.SilkS")
		)
		(fp_line
			(start -0.7874 0.4064)
			(end -0.7874 -0.4064)
			(stroke
				(width 0.1524)
				(type default)
			)
			(layer "F.SilkS")
		)
		(fp_line
			(start -0.12065 -0.305054)
			(end -0.12065 -0.2794)
			(stroke
				(width 0.1)
				(type default)
			)
			(layer "F.Fab")
		)
		(fp_line
			(start -0.67945 -0.305054)
			(end -0.12065 -0.305054)
			(stroke
				(width 0.1)
				(type default)
			)
			(layer "F.Fab")
		)
		(fp_line
			(start 0.67945 -0.3048)
			(end 0.67945 0.3048)
			(stroke
				(width 0.1)
				(type default)
			)
			(layer "F.Fab")
		)
		(fp_line
			(start 0.12065 -0.3048)
			(end 0.67945 -0.3048)
			(stroke
				(width 0.1)
				(type default)
			)
			(layer "F.Fab")
		)
		(fp_line
			(start 0.12065 -0.2794)
			(end 0.12065 -0.3048)
			(stroke
				(width 0.1)
				(type default)
			)
			(layer "F.Fab")
		)
		(fp_line
			(start -0.12065 -0.2794)
			(end 0.12065 -0.2794)
			(stroke
				(width 0.1)
				(type default)
			)
			(layer "F.Fab")
		)
		(fp_line
			(start 0.120396 0.2794)
			(end -0.12065 0.2794)
			(stroke
				(width 0.1)
				(type default)
			)
			(layer "F.Fab")
		)
		(fp_line
			(start -0.12065 0.2794)
			(end -0.12065 0.3048)
			(stroke
				(width 0.1)
				(type default)
			)
			(layer "F.Fab")
		)
		(fp_line
			(start 0.67945 0.3048)
			(end 0.120396 0.3048)
			(stroke
				(width 0.1)
				(type default)
			)
			(layer "F.Fab")
		)
		(fp_line
			(start 0.120396 0.3048)
			(end 0.120396 0.2794)
			(stroke
				(width 0.1)
				(type default)
			)
			(layer "F.Fab")
		)
		(fp_line
			(start -0.12065 0.3048)
			(end -0.67945 0.3048)
			(stroke
				(width 0.1)
				(type default)
			)
			(layer "F.Fab")
		)
		(fp_line
			(start -0.67945 0.3048)
			(end -0.67945 -0.305054)
			(stroke
				(width 0.1)
				(type default)
			)
			(layer "F.Fab")
		)
		(pad "1" smd circle
			(at -0.40005 0 90)
			(size 0 0)
			(layers "F.Cu" "F.Mask" "F.Paste")
			(net "P12V_E1S_SENSE_0")
		)
		(pad "2" smd circle
			(at 0.40005 0 90)
			(size 0 0)
			(layers "F.Cu" "F.Mask" "F.Paste")
			(net "GND")
		)
	)
	(footprint ""
		(layer "F.Cu")
		(at 448.672458 -93.509592 180)
		(property "Reference" "R3617"
			(at 0 0 180)
			(layer "F.SilkS")
			(hide yes)
			(effects
				(font
					(size 1.27 1.27)
				)
			)
		)
		(property "Value" ""
			(at 0 0 180)
			(layer "F.Fab")
			(effects
				(font
					(size 1.27 1.27)
				)
			)
		)
		(duplicate_pad_numbers_are_jumpers no)
		(fp_line
			(start 0.7874 0.4064)
			(end -0.7874 0.4064)
			(stroke
				(width 0.1524)
				(type default)
			)
			(layer "F.SilkS")
		)
		(fp_line
			(start 0.7874 -0.4064)
			(end 0.7874 0.4064)
			(stroke
				(width 0.1524)
				(type default)
			)
			(layer "F.SilkS")
		)
		(fp_line
			(start -0.7874 0.4064)
			(end -0.7874 -0.4064)
			(stroke
				(width 0.1524)
				(type default)
			)
			(layer "F.SilkS")
		)
		(fp_line
			(start -0.7874 -0.4064)
			(end 0.7874 -0.4064)
			(stroke
				(width 0.1524)
				(type default)
			)
			(layer "F.SilkS")
		)
		(fp_line
			(start 0.67945 0.3048)
			(end 0.120396 0.3048)
			(stroke
				(width 0.1)
				(type default)
			)
			(layer "F.Fab")
		)
		(fp_line
			(start 0.67945 -0.3048)
			(end 0.67945 0.3048)
			(stroke
				(width 0.1)
				(type default)
			)
			(layer "F.Fab")
		)
		(fp_line
			(start 0.12065 -0.2794)
			(end 0.12065 -0.3048)
			(stroke
				(width 0.1)
				(type default)
			)
			(layer "F.Fab")
		)
		(fp_line
			(start 0.12065 -0.3048)
			(end 0.67945 -0.3048)
			(stroke
				(width 0.1)
				(type default)
			)
			(layer "F.Fab")
		)
		(fp_line
			(start 0.120396 0.3048)
			(end 0.120396 0.2794)
			(stroke
				(width 0.1)
				(type default)
			)
			(layer "F.Fab")
		)
		(fp_line
			(start 0.120396 0.2794)
			(end -0.12065 0.2794)
			(stroke
				(width 0.1)
				(type default)
			)
			(layer "F.Fab")
		)
		(fp_line
			(start -0.12065 0.3048)
			(end -0.67945 0.3048)
			(stroke
				(width 0.1)
				(type default)
			)
			(layer "F.Fab")
		)
		(fp_line
			(start -0.12065 0.2794)
			(end -0.12065 0.3048)
			(stroke
				(width 0.1)
				(type default)
			)
			(layer "F.Fab")
		)
		(fp_line
			(start -0.12065 -0.2794)
			(end 0.12065 -0.2794)
			(stroke
				(width 0.1)
				(type default)
			)
			(layer "F.Fab")
		)
		(fp_line
			(start -0.12065 -0.305054)
			(end -0.12065 -0.2794)
			(stroke
				(width 0.1)
				(type default)
			)
			(layer "F.Fab")
		)
		(fp_line
			(start -0.67945 0.3048)
			(end -0.67945 -0.305054)
			(stroke
				(width 0.1)
				(type default)
			)
			(layer "F.Fab")
		)
		(fp_line
			(start -0.67945 -0.305054)
			(end -0.12065 -0.305054)
			(stroke
				(width 0.1)
				(type default)
			)
			(layer "F.Fab")
		)
		(pad "1" smd circle
			(at -0.40005 0 180)
			(size 0 0)
			(layers "F.Cu" "F.Mask" "F.Paste")
			(net "GND")
		)
		(pad "2" smd circle
			(at 0.40005 0 180)
			(size 0 0)
			(layers "F.Cu" "F.Mask" "F.Paste")
			(net "INA230_1_A0")
		)
	)
	(footprint ""
		(layer "F.Cu")
		(at 102.268782 -376.982228)
		(property "Reference" "C713"
			(at 0 0 0)
			(layer "F.SilkS")
			(hide yes)
			(effects
				(font
					(size 1.27 1.27)
				)
			)
		)
		(property "Value" ""
			(at 0 0 0)
			(layer "F.Fab")
			(effects
				(font
					(size 1.27 1.27)
				)
			)
		)
		(duplicate_pad_numbers_are_jumpers no)
		(fp_line
			(start -0.299974 -0.150114)
			(end 0.299974 -0.150114)
			(stroke
				(width 0.1)
				(type default)
			)
			(layer "F.Fab")
		)
		(fp_line
			(start -0.299974 0.150114)
			(end -0.299974 -0.150114)
			(stroke
				(width 0.1)
				(type default)
			)
			(layer "F.Fab")
		)
		(fp_line
			(start 0.299974 -0.150114)
			(end 0.299974 0.150114)
			(stroke
				(width 0.1)
				(type default)
			)
			(layer "F.Fab")
		)
		(fp_line
			(start 0.299974 0.150114)
			(end -0.299974 0.150114)
			(stroke
				(width 0.1)
				(type default)
			)
			(layer "F.Fab")
		)
		(pad "1" smd rect
			(at -0.2667 0)
			(size 0.3048 0.381)
			(layers "F.Cu" "F.Mask" "F.Paste")
			(net "P5E_CPU1_P1_TX_C_DP<14>")
		)
		(pad "2" smd rect
			(at 0.2667 0)
			(size 0.3048 0.381)
			(layers "F.Cu" "F.Mask" "F.Paste")
			(net "P5E_CPU1_P1_TX_DP<14>")
		)
	)
)
